FILE_TYPE = MACRO_DRAWING;
SET COLOR_WIRE YELLOW;
SET COLOR_PROP MONO;
SET COLOR_DOT WHITE;
SET COLOR_ARC YELLOW;
SET COLOR_BODY GREEN;
SET COLOR_NOTE MONO;
SET PROP_DISPLAY VALUE;
SET PAGE_NUMBER P70;
FORCEADD SKX_EXT_B..17
(-2925 2575);
FORCEPROP 1 LAST LOCATION U2D1
J 0
(-3575 3325);
DISPLAY 0.617021 (-3575 3325);
PAINT AQUA (-3575 3325);
FORCEPROP 1 LAST PART_NUMBER TBD
J 0
(-3575 2025);
DISPLAY 0.617021 (-3575 2025);
PAINT BLUE (-3575 2025);
FORCEPROP 1 LAST MATERIAL IC
J 0
(-3575 3275);
DISPLAY 0.617021 (-3575 3275);
PAINT SKYBLUE (-3575 3275);
FORCEPROP 2 LASTPIN (-2225 2875) $PN AW22
J 0
(-2215 2885);
DISPLAY 0.617021 (-2215 2885);
PAINT ORANGE (-2215 2885);
FORCEPROP 2 LASTPIN (-2225 2925) $PN AW20
J 0
(-2215 2935);
DISPLAY 0.617021 (-2215 2935);
PAINT ORANGE (-2215 2935);
FORCEPROP 2 LASTPIN (-2225 2975) $PN AW16
J 0
(-2215 2985);
DISPLAY 0.617021 (-2215 2985);
PAINT ORANGE (-2215 2985);
FORCEPROP 2 LASTPIN (-2225 3025) $PN AU18
J 0
(-2215 3035);
DISPLAY 0.617021 (-2215 3035);
PAINT ORANGE (-2215 3035);
FORCEPROP 2 LASTPIN (-2225 3075) $PN AR16
J 0
(-2215 3085);
DISPLAY 0.617021 (-2215 3085);
PAINT ORANGE (-2215 3085);
FORCEPROP 2 LASTPIN (-2225 2775) $PN CH25
J 0
(-2215 2785);
DISPLAY 0.617021 (-2215 2785);
PAINT ORANGE (-2215 2785);
FORCEPROP 2 LASTPIN (-2225 2725) $PN CH77
J 0
(-2215 2735);
DISPLAY 0.617021 (-2215 2735);
PAINT ORANGE (-2215 2735);
FORCEPROP 2 LASTPIN (-2225 2625) $PN CJ20
J 0
(-2215 2635);
DISPLAY 0.617021 (-2215 2635);
PAINT ORANGE (-2215 2635);
FORCEPROP 2 LASTPIN (-2225 2575) $PN CJ22
J 0
(-2215 2585);
DISPLAY 0.617021 (-2215 2585);
PAINT ORANGE (-2215 2585);
FORCEPROP 2 LASTPIN (-2225 2525) $PN CJ24
J 0
(-2215 2535);
DISPLAY 0.617021 (-2215 2535);
PAINT ORANGE (-2215 2535);
FORCEPROP 2 LASTPIN (-2225 2475) $PN CJ26
J 0
(-2215 2485);
DISPLAY 0.617021 (-2215 2485);
PAINT ORANGE (-2215 2485);
FORCEPROP 2 LASTPIN (-2225 2425) $PN CK19
J 0
(-2215 2435);
DISPLAY 0.617021 (-2215 2435);
PAINT ORANGE (-2215 2435);
FORCEPROP 2 LASTPIN (-2225 2375) $PN CK23
J 0
(-2215 2385);
DISPLAY 0.617021 (-2215 2385);
PAINT ORANGE (-2215 2385);
FORCEPROP 2 LASTPIN (-2225 2325) $PN CK25
J 0
(-2215 2335);
DISPLAY 0.617021 (-2215 2335);
PAINT ORANGE (-2215 2335);
FORCEPROP 2 LASTPIN (-2225 2275) $PN CK77
J 0
(-2215 2285);
DISPLAY 0.617021 (-2215 2285);
PAINT ORANGE (-2215 2285);
FORCEPROP 2 LASTPIN (-2225 2225) $PN CL24
J 0
(-2215 2235);
DISPLAY 0.617021 (-2215 2235);
PAINT ORANGE (-2215 2235);
FORCEPROP 1 LAST PACK_TYPE BGA1
J 0
(-3575 3375);
PAINT SKYBLUE (-3575 3375);
DISPLAY INVISIBLE (-3575 3375);
FORCEPROP 2 LAST SEC_TYPE BGA1
J 0
(-3575 3375);
DISPLAY 1.021277 (-3575 3375);
PAINT ORANGE (-3575 3375);
DISPLAY INVISIBLE (-3575 3375);
FORCEPROP 2 LAST CDS_LIB chpset_lib
J 0
(-2925 2575);
PAINT ORANGE (-2925 2575);
DISPLAY INVISIBLE (-2925 2575);
FORCEPROP 2 LAST SEC 17
J 0
(-3575 3375);
DISPLAY 0.680851 (-3575 3375);
PAINT MONO (-3575 3375);
DISPLAY INVISIBLE (-3575 3375);
FORCEPROP 2 LAST CDS_LOCATION U2D1
J 0
(-3575 3325);
DISPLAY 0.617021 (-3575 3325);
PAINT AQUA (-3575 3325);
DISPLAY INVISIBLE (-3575 3325);
FORCEPROP 1 LAST PATH I10
J 0
(-2925 3275);
PAINT GREEN (-2925 3275);
DISPLAY INVISIBLE (-2925 3275);
FORCEADD OFFPAGE..1
(-7025 3350);
FORCEPROP 2 LAST $XR0 103 
J 0
(-7277 3350);
DISPLAY 0.638298 (-7277 3350);
PAINT MONO (-7277 3350);
FORCEPROP 2 LAST CDS_LIB mstr_standard
J 0
(-7025 3350);
PAINT MONO (-7025 3350);
DISPLAY INVISIBLE (-7025 3350);
FORCEPROP 1 LAST OFFPAGE TRUE
J 0
(-6700 3225);
DISPLAY 0.872340 (-6700 3225);
PAINT GREEN (-6700 3225);
DISPLAY INVISIBLE (-6700 3225);
FORCEPROP 1 LAST COMMENT_BODY TRUE
J 0
(-6900 3250);
DISPLAY 0.872340 (-6900 3250);
PAINT GREEN (-6900 3250);
DISPLAY INVISIBLE (-6900 3250);
FORCEPROP 2 LAST PATH I11
J 0
(-7275 3400);
DISPLAY 1.021277 (-7275 3400);
PAINT ORANGE (-7275 3400);
DISPLAY INVISIBLE (-7275 3400);
FORCEADD VCC_CORE..1
(-1225 2825);
FORCEPROP 3 LASTPIN (-1225 2775) SIG_NAME PVCCMCP_CPU1\g
J 0
(-1215 2785);
DISPLAY 0.659574 (-1215 2785);
PAINT MONO (-1215 2785);
DISPLAY INVISIBLE (-1215 2785);
FORCEPROP 1 LAST HDL_POWER PVCCMCP_CPU1
J 1
(-1225 2875);
DISPLAY 0.617021 (-1225 2875);
PAINT GREEN (-1225 2875);
FORCEPROP 2 LAST CDS_LIB mstr_symbols
J 0
(-1225 2825);
PAINT ORANGE (-1225 2825);
DISPLAY INVISIBLE (-1225 2825);
FORCEPROP 1 LAST PATH I12
J 0
(-1175 2850);
DISPLAY 0.872340 (-1175 2850);
PAINT AQUA (-1175 2850);
DISPLAY INVISIBLE (-1175 2850);
FORCEADD VCC_CORE..1
(-4000 3775);
FORCEPROP 3 LASTPIN (-4000 3725) SIG_NAME PVCCMCP_CPU1\g
J 0
(-3990 3735);
DISPLAY 0.659574 (-3990 3735);
PAINT MONO (-3990 3735);
DISPLAY INVISIBLE (-3990 3735);
FORCEPROP 1 LAST HDL_POWER PVCCMCP_CPU1
J 1
(-4000 3825);
DISPLAY 0.617021 (-4000 3825);
PAINT GREEN (-4000 3825);
FORCEPROP 2 LAST CDS_LIB mstr_symbols
J 0
(-4000 3775);
PAINT ORANGE (-4000 3775);
DISPLAY INVISIBLE (-4000 3775);
FORCEPROP 1 LAST PATH I13
J 0
(-3950 3800);
DISPLAY 0.872340 (-3950 3800);
PAINT AQUA (-3950 3800);
DISPLAY INVISIBLE (-3950 3800);
FORCEADD VCC_CORE..1
(-7125 2350);
FORCEPROP 3 LASTPIN (-7125 2300) SIG_NAME PVCCMCP_CPU1\g
J 0
(-7115 2310);
DISPLAY 0.659574 (-7115 2310);
PAINT MONO (-7115 2310);
DISPLAY INVISIBLE (-7115 2310);
FORCEPROP 1 LAST HDL_POWER PVCCMCP_CPU1
J 1
(-7125 2400);
DISPLAY 0.617021 (-7125 2400);
PAINT GREEN (-7125 2400);
FORCEPROP 2 LAST CDS_LIB mstr_symbols
J 0
(-7125 2350);
PAINT ORANGE (-7125 2350);
DISPLAY INVISIBLE (-7125 2350);
FORCEPROP 1 LAST PATH I15
J 0
(-7075 2375);
DISPLAY 0.872340 (-7075 2375);
PAINT AQUA (-7075 2375);
DISPLAY INVISIBLE (-7075 2375);
FORCEADD OFFPAGE..1
(-7025 2750);
FORCEPROP 2 LAST $XR0 103 
J 0
(-7277 2750);
DISPLAY 0.638298 (-7277 2750);
PAINT MONO (-7277 2750);
FORCEPROP 2 LAST CDS_LIB mstr_standard
J 0
(-7025 2750);
PAINT MONO (-7025 2750);
DISPLAY INVISIBLE (-7025 2750);
FORCEPROP 1 LAST OFFPAGE TRUE
J 0
(-6700 2625);
DISPLAY 0.872340 (-6700 2625);
PAINT GREEN (-6700 2625);
DISPLAY INVISIBLE (-6700 2625);
FORCEPROP 1 LAST COMMENT_BODY TRUE
J 0
(-6900 2650);
DISPLAY 0.872340 (-6900 2650);
PAINT GREEN (-6900 2650);
DISPLAY INVISIBLE (-6900 2650);
FORCEPROP 2 LAST PATH I7
J 0
(-7300 2800);
DISPLAY 1.021277 (-7300 2800);
PAINT ORANGE (-7300 2800);
DISPLAY INVISIBLE (-7300 2800);
FORCEADD SKX_EXT_B..16
(-5450 2550);
FORCEPROP 1 LAST LOCATION U2D1
J 0
(-6000 3900);
DISPLAY 0.617021 (-6000 3900);
PAINT AQUA (-6000 3900);
FORCEPROP 1 LAST PART_NUMBER TBD
J 0
(-6000 1250);
DISPLAY 0.617021 (-6000 1250);
PAINT BLUE (-6000 1250);
FORCEPROP 1 LAST MATERIAL IC
J 0
(-6000 3850);
DISPLAY 0.617021 (-6000 3850);
PAINT SKYBLUE (-6000 3850);
FORCEPROP 2 LASTPIN (-4850 1900) $PN AY83
J 0
(-4840 1910);
DISPLAY 0.617021 (-4840 1910);
PAINT ORANGE (-4840 1910);
FORCEPROP 2 LASTPIN (-6050 3650) $PN BA78
J 2
(-6060 3660);
DISPLAY 0.617021 (-6060 3660);
PAINT ORANGE (-6060 3660);
FORCEPROP 2 LASTPIN (-6050 3600) $PN BA82
J 2
(-6060 3610);
DISPLAY 0.617021 (-6060 3610);
PAINT ORANGE (-6060 3610);
FORCEPROP 2 LASTPIN (-6050 3550) $PN BB13
J 2
(-6060 3560);
DISPLAY 0.617021 (-6060 3560);
PAINT ORANGE (-6060 3560);
FORCEPROP 2 LASTPIN (-6050 3500) $PN BB15
J 2
(-6060 3510);
DISPLAY 0.617021 (-6060 3510);
PAINT ORANGE (-6060 3510);
FORCEPROP 2 LASTPIN (-6050 3450) $PN BB17
J 2
(-6060 3460);
DISPLAY 0.617021 (-6060 3460);
PAINT ORANGE (-6060 3460);
FORCEPROP 2 LASTPIN (-6050 3400) $PN BB21
J 2
(-6060 3410);
DISPLAY 0.617021 (-6060 3410);
PAINT ORANGE (-6060 3410);
FORCEPROP 2 LASTPIN (-6050 3350) $PN BB25
J 2
(-6060 3360);
DISPLAY 0.617021 (-6060 3360);
PAINT ORANGE (-6060 3360);
FORCEPROP 2 LASTPIN (-6050 3300) $PN BB65
J 2
(-6060 3310);
DISPLAY 0.617021 (-6060 3310);
PAINT ORANGE (-6060 3310);
FORCEPROP 2 LASTPIN (-6050 3250) $PN BB67
J 2
(-6060 3260);
DISPLAY 0.617021 (-6060 3260);
PAINT ORANGE (-6060 3260);
FORCEPROP 2 LASTPIN (-6050 3200) $PN BC14
J 2
(-6060 3210);
DISPLAY 0.617021 (-6060 3210);
PAINT ORANGE (-6060 3210);
FORCEPROP 2 LASTPIN (-6050 3150) $PN BC18
J 2
(-6060 3160);
DISPLAY 0.617021 (-6060 3160);
PAINT ORANGE (-6060 3160);
FORCEPROP 2 LASTPIN (-6050 3100) $PN BC20
J 2
(-6060 3110);
DISPLAY 0.617021 (-6060 3110);
PAINT ORANGE (-6060 3110);
FORCEPROP 2 LASTPIN (-6050 3050) $PN BC22
J 2
(-6060 3060);
DISPLAY 0.617021 (-6060 3060);
PAINT ORANGE (-6060 3060);
FORCEPROP 2 LASTPIN (-6050 3000) $PN BC64
J 2
(-6060 3010);
DISPLAY 0.617021 (-6060 3010);
PAINT ORANGE (-6060 3010);
FORCEPROP 2 LASTPIN (-6050 2950) $PN BC66
J 2
(-6060 2960);
DISPLAY 0.617021 (-6060 2960);
PAINT ORANGE (-6060 2960);
FORCEPROP 2 LASTPIN (-6050 2900) $PN BC68
J 2
(-6060 2910);
DISPLAY 0.617021 (-6060 2910);
PAINT ORANGE (-6060 2910);
FORCEPROP 2 LASTPIN (-6050 2850) $PN BD17
J 2
(-6060 2860);
DISPLAY 0.617021 (-6060 2860);
PAINT ORANGE (-6060 2860);
FORCEPROP 2 LASTPIN (-6050 2800) $PN BD19
J 2
(-6060 2810);
DISPLAY 0.617021 (-6060 2810);
PAINT ORANGE (-6060 2810);
FORCEPROP 2 LASTPIN (-6050 2750) $PN BD25
J 2
(-6060 2760);
DISPLAY 0.617021 (-6060 2760);
PAINT ORANGE (-6060 2760);
FORCEPROP 2 LASTPIN (-6050 2650) $PN BD67
J 2
(-6060 2660);
DISPLAY 0.617021 (-6060 2660);
PAINT ORANGE (-6060 2660);
FORCEPROP 2 LASTPIN (-6050 2600) $PN BD69
J 2
(-6060 2610);
DISPLAY 0.617021 (-6060 2610);
PAINT ORANGE (-6060 2610);
FORCEPROP 2 LASTPIN (-6050 2550) $PN BE18
J 2
(-6060 2560);
DISPLAY 0.617021 (-6060 2560);
PAINT ORANGE (-6060 2560);
FORCEPROP 2 LASTPIN (-6050 2500) $PN BE20
J 2
(-6060 2510);
DISPLAY 0.617021 (-6060 2510);
PAINT ORANGE (-6060 2510);
FORCEPROP 2 LASTPIN (-6050 2450) $PN BE22
J 2
(-6060 2460);
DISPLAY 0.617021 (-6060 2460);
PAINT ORANGE (-6060 2460);
FORCEPROP 2 LASTPIN (-6050 2400) $PN BF21
J 2
(-6060 2410);
DISPLAY 0.617021 (-6060 2410);
PAINT ORANGE (-6060 2410);
FORCEPROP 2 LASTPIN (-6050 2350) $PN BG18
J 2
(-6060 2360);
DISPLAY 0.617021 (-6060 2360);
PAINT ORANGE (-6060 2360);
FORCEPROP 2 LASTPIN (-6050 2300) $PN BG20
J 2
(-6060 2310);
DISPLAY 0.617021 (-6060 2310);
PAINT ORANGE (-6060 2310);
FORCEPROP 2 LASTPIN (-6050 2250) $PN BH19
J 2
(-6060 2260);
DISPLAY 0.617021 (-6060 2260);
PAINT ORANGE (-6060 2260);
FORCEPROP 2 LASTPIN (-6050 2200) $PN BJ16
J 2
(-6060 2210);
DISPLAY 0.617021 (-6060 2210);
PAINT ORANGE (-6060 2210);
FORCEPROP 2 LASTPIN (-6050 2150) $PN BJ18
J 2
(-6060 2160);
DISPLAY 0.617021 (-6060 2160);
PAINT ORANGE (-6060 2160);
FORCEPROP 2 LASTPIN (-6050 2100) $PN BJ20
J 2
(-6060 2110);
DISPLAY 0.617021 (-6060 2110);
PAINT ORANGE (-6060 2110);
FORCEPROP 2 LASTPIN (-6050 2050) $PN BK17
J 2
(-6060 2060);
DISPLAY 0.617021 (-6060 2060);
PAINT ORANGE (-6060 2060);
FORCEPROP 2 LASTPIN (-6050 2000) $PN BL18
J 2
(-6060 2010);
DISPLAY 0.617021 (-6060 2010);
PAINT ORANGE (-6060 2010);
FORCEPROP 2 LASTPIN (-6050 1950) $PN BL20
J 2
(-6060 1960);
DISPLAY 0.617021 (-6060 1960);
PAINT ORANGE (-6060 1960);
FORCEPROP 2 LASTPIN (-6050 1900) $PN BM17
J 2
(-6060 1910);
DISPLAY 0.617021 (-6060 1910);
PAINT ORANGE (-6060 1910);
FORCEPROP 2 LASTPIN (-6050 1850) $PN BM19
J 2
(-6060 1860);
DISPLAY 0.617021 (-6060 1860);
PAINT ORANGE (-6060 1860);
FORCEPROP 2 LASTPIN (-6050 1800) $PN BN18
J 2
(-6060 1810);
DISPLAY 0.617021 (-6060 1810);
PAINT ORANGE (-6060 1810);
FORCEPROP 2 LASTPIN (-6050 1750) $PN BP17
J 2
(-6060 1760);
DISPLAY 0.617021 (-6060 1760);
PAINT ORANGE (-6060 1760);
FORCEPROP 2 LASTPIN (-6050 1700) $PN BP21
J 2
(-6060 1710);
DISPLAY 0.617021 (-6060 1710);
PAINT ORANGE (-6060 1710);
FORCEPROP 2 LASTPIN (-6050 1650) $PN BR22
J 2
(-6060 1660);
DISPLAY 0.617021 (-6060 1660);
PAINT ORANGE (-6060 1660);
FORCEPROP 2 LASTPIN (-6050 1600) $PN BR24
J 2
(-6060 1610);
DISPLAY 0.617021 (-6060 1610);
PAINT ORANGE (-6060 1610);
FORCEPROP 2 LASTPIN (-6050 1550) $PN BU18
J 2
(-6060 1560);
DISPLAY 0.617021 (-6060 1560);
PAINT ORANGE (-6060 1560);
FORCEPROP 2 LASTPIN (-6050 1500) $PN BU20
J 2
(-6060 1510);
DISPLAY 0.617021 (-6060 1510);
PAINT ORANGE (-6060 1510);
FORCEPROP 2 LASTPIN (-6050 1450) $PN BU22
J 2
(-6060 1460);
DISPLAY 0.617021 (-6060 1460);
PAINT ORANGE (-6060 1460);
FORCEPROP 2 LASTPIN (-4850 3650) $PN BV19
J 0
(-4840 3660);
DISPLAY 0.617021 (-4840 3660);
PAINT ORANGE (-4840 3660);
FORCEPROP 2 LASTPIN (-4850 3600) $PN BV21
J 0
(-4840 3610);
DISPLAY 0.617021 (-4840 3610);
PAINT ORANGE (-4840 3610);
FORCEPROP 2 LASTPIN (-4850 3550) $PN BV23
J 0
(-4840 3560);
DISPLAY 0.617021 (-4840 3560);
PAINT ORANGE (-4840 3560);
FORCEPROP 2 LASTPIN (-4850 3500) $PN BW10
J 0
(-4840 3510);
DISPLAY 0.617021 (-4840 3510);
PAINT ORANGE (-4840 3510);
FORCEPROP 2 LASTPIN (-4850 3450) $PN BW20
J 0
(-4840 3460);
DISPLAY 0.617021 (-4840 3460);
PAINT ORANGE (-4840 3460);
FORCEPROP 2 LASTPIN (-4850 3400) $PN BW22
J 0
(-4840 3410);
DISPLAY 0.617021 (-4840 3410);
PAINT ORANGE (-4840 3410);
FORCEPROP 2 LASTPIN (-4850 3350) $PN BY19
J 0
(-4840 3360);
DISPLAY 0.617021 (-4840 3360);
PAINT ORANGE (-4840 3360);
FORCEPROP 2 LASTPIN (-4850 3300) $PN BY25
J 0
(-4840 3310);
DISPLAY 0.617021 (-4840 3310);
PAINT ORANGE (-4840 3310);
FORCEPROP 2 LASTPIN (-4850 3250) $PN CA22
J 0
(-4840 3260);
DISPLAY 0.617021 (-4840 3260);
PAINT ORANGE (-4840 3260);
FORCEPROP 2 LASTPIN (-4850 3200) $PN CA24
J 0
(-4840 3210);
DISPLAY 0.617021 (-4840 3210);
PAINT ORANGE (-4840 3210);
FORCEPROP 2 LASTPIN (-4850 3150) $PN CB19
J 0
(-4840 3160);
DISPLAY 0.617021 (-4840 3160);
PAINT ORANGE (-4840 3160);
FORCEPROP 2 LASTPIN (-4850 3100) $PN CB21
J 0
(-4840 3110);
DISPLAY 0.617021 (-4840 3110);
PAINT ORANGE (-4840 3110);
FORCEPROP 2 LASTPIN (-4850 3050) $PN CB25
J 0
(-4840 3060);
DISPLAY 0.617021 (-4840 3060);
PAINT ORANGE (-4840 3060);
FORCEPROP 2 LASTPIN (-4850 3000) $PN CB5
J 0
(-4840 3010);
DISPLAY 0.617021 (-4840 3010);
PAINT ORANGE (-4840 3010);
FORCEPROP 2 LASTPIN (-4850 2950) $PN CC20
J 0
(-4840 2960);
DISPLAY 0.617021 (-4840 2960);
PAINT ORANGE (-4840 2960);
FORCEPROP 2 LASTPIN (-4850 2900) $PN CC6
J 0
(-4840 2910);
DISPLAY 0.617021 (-4840 2910);
PAINT ORANGE (-4840 2910);
FORCEPROP 2 LASTPIN (-4850 2850) $PN CD19
J 0
(-4840 2860);
DISPLAY 0.617021 (-4840 2860);
PAINT ORANGE (-4840 2860);
FORCEPROP 2 LASTPIN (-4850 2800) $PN CD21
J 0
(-4840 2810);
DISPLAY 0.617021 (-4840 2810);
PAINT ORANGE (-4840 2810);
FORCEPROP 2 LASTPIN (-4850 2750) $PN CD25
J 0
(-4840 2760);
DISPLAY 0.617021 (-4840 2760);
PAINT ORANGE (-4840 2760);
FORCEPROP 2 LASTPIN (-4850 2700) $PN CE22
J 0
(-4840 2710);
DISPLAY 0.617021 (-4840 2710);
PAINT ORANGE (-4840 2710);
FORCEPROP 2 LASTPIN (-4850 2650) $PN CE78
J 0
(-4840 2660);
DISPLAY 0.617021 (-4840 2660);
PAINT ORANGE (-4840 2660);
FORCEPROP 2 LASTPIN (-4850 2600) $PN CE80
J 0
(-4840 2610);
DISPLAY 0.617021 (-4840 2610);
PAINT ORANGE (-4840 2610);
FORCEPROP 2 LASTPIN (-4850 2550) $PN CF19
J 0
(-4840 2560);
DISPLAY 0.617021 (-4840 2560);
PAINT ORANGE (-4840 2560);
FORCEPROP 2 LASTPIN (-4850 2500) $PN CF21
J 0
(-4840 2510);
DISPLAY 0.617021 (-4840 2510);
PAINT ORANGE (-4840 2510);
FORCEPROP 2 LASTPIN (-4850 2450) $PN CF23
J 0
(-4840 2460);
DISPLAY 0.617021 (-4840 2460);
PAINT ORANGE (-4840 2460);
FORCEPROP 2 LASTPIN (-4850 2400) $PN CF79
J 0
(-4840 2410);
DISPLAY 0.617021 (-4840 2410);
PAINT ORANGE (-4840 2410);
FORCEPROP 2 LASTPIN (-4850 2350) $PN CF81
J 0
(-4840 2360);
DISPLAY 0.617021 (-4840 2360);
PAINT ORANGE (-4840 2360);
FORCEPROP 2 LASTPIN (-4850 2300) $PN CG10
J 0
(-4840 2310);
DISPLAY 0.617021 (-4840 2310);
PAINT ORANGE (-4840 2310);
FORCEPROP 2 LASTPIN (-4850 2250) $PN CG20
J 0
(-4840 2260);
DISPLAY 0.617021 (-4840 2260);
PAINT ORANGE (-4840 2260);
FORCEPROP 2 LASTPIN (-4850 2200) $PN CG24
J 0
(-4840 2210);
DISPLAY 0.617021 (-4840 2210);
PAINT ORANGE (-4840 2210);
FORCEPROP 2 LASTPIN (-4850 2150) $PN CG26
J 0
(-4840 2160);
DISPLAY 0.617021 (-4840 2160);
PAINT ORANGE (-4840 2160);
FORCEPROP 2 LASTPIN (-4850 2100) $PN CG78
J 0
(-4840 2110);
DISPLAY 0.617021 (-4840 2110);
PAINT ORANGE (-4840 2110);
FORCEPROP 2 LASTPIN (-4850 2050) $PN CG82
J 0
(-4840 2060);
DISPLAY 0.617021 (-4840 2060);
PAINT ORANGE (-4840 2060);
FORCEPROP 2 LASTPIN (-4850 2000) $PN CH21
J 0
(-4840 2010);
DISPLAY 0.617021 (-4840 2010);
PAINT ORANGE (-4840 2010);
FORCEPROP 2 LASTPIN (-4850 1950) $PN CH23
J 0
(-4840 1960);
DISPLAY 0.617021 (-4840 1960);
PAINT ORANGE (-4840 1960);
FORCEPROP 2 LASTPIN (-6050 2700) $PN BD65
J 2
(-6060 2710);
DISPLAY 0.617021 (-6060 2710);
PAINT ORANGE (-6060 2710);
FORCEPROP 1 LAST PACK_TYPE BGA1
J 0
(-6000 3950);
PAINT SKYBLUE (-6000 3950);
DISPLAY INVISIBLE (-6000 3950);
FORCEPROP 2 LAST SEC_TYPE BGA1
J 0
(-6000 3950);
DISPLAY 1.021277 (-6000 3950);
PAINT ORANGE (-6000 3950);
DISPLAY INVISIBLE (-6000 3950);
FORCEPROP 2 LAST CDS_LIB chpset_lib
J 0
(-5450 2550);
PAINT ORANGE (-5450 2550);
DISPLAY INVISIBLE (-5450 2550);
FORCEPROP 2 LAST SEC 16
J 0
(-6000 3950);
DISPLAY 0.680851 (-6000 3950);
PAINT MONO (-6000 3950);
DISPLAY INVISIBLE (-6000 3950);
FORCEPROP 2 LAST CDS_LOCATION U2D1
J 0
(-6000 3900);
DISPLAY 0.617021 (-6000 3900);
PAINT AQUA (-6000 3900);
DISPLAY INVISIBLE (-6000 3900);
FORCEPROP 1 LAST PATH I9
J 0
(-5450 3850);
PAINT GREEN (-5450 3850);
DISPLAY INVISIBLE (-5450 3850);
FORCEADD PRELIM..10
(-3090 2715);
PAINT GRAY (-3090 2715);
FORCEPROP 2 LAST CDS_LIB mstr_misc
J 0
(-3090 2715);
PAINT ORANGE (-3090 2715);
DISPLAY INVISIBLE (-3090 2715);
FORCEPROP 1 LAST COMMENT_BODY TRUE
J 0
(-3090 2715);
PAINT ORANGE (-3090 2715);
DISPLAY INVISIBLE (-3090 2715);
FORCEADD DESIGN_NOTE..1
(-4225 1600);
FORCEPROP 0 LAST L1 CPU SYMBOLS 1-30 ARE PRELIMINARY AND SUBJECT TO CHANGE
J 0
(-4425 1475);
DISPLAY 1.021277 (-4425 1475);
PAINT ORANGE (-4425 1475);
FORCEPROP 2 LAST CDS_LIB mstr_symbols
J 0
(-4225 1600);
PAINT ORANGE (-4225 1600);
DISPLAY INVISIBLE (-4225 1600);
FORCEPROP 1 LAST COMMENT_BODY TRUE
J 0
(-4200 1700);
DISPLAY 0.978723 (-4200 1700);
PAINT ORANGE (-4200 1700);
DISPLAY INVISIBLE (-4200 1700);
FORCEADD PRELIM..10
(-5465 2665);
PAINT GRAY (-5465 2665);
FORCEPROP 2 LAST CDS_LIB mstr_misc
J 0
(-5465 2665);
PAINT ORANGE (-5465 2665);
DISPLAY INVISIBLE (-5465 2665);
FORCEPROP 1 LAST COMMENT_BODY TRUE
J 0
(-5465 2665);
PAINT ORANGE (-5465 2665);
DISPLAY INVISIBLE (-5465 2665);
FORCEADD INTEL_CORP_BPAGE..1
(0 0);
FORCEPROP 1 LAST CDS_CON_LAST_MODIFIED Tue Dec 01 11:51:38 2015
J 0
(-1425 325);
DISPLAY 1.340426 (-1425 325);
PAINT GREEN (-1425 325);
DISPLAY INVISIBLE (-1425 325);
FORCEPROP 1 LAST CUSTOM_TXT_CDS <CURRENT_DESIGN_SHEET> OF <TOTAL_DESIGN_SHEETS>
J 0
(-500 25);
PAINT GREEN (-500 25);
FORCEPROP 1 LAST CUSTOM_TXT_CDS <CON_LAST_MODIFIED>
J 0
(-1925 350);
PAINT GREEN (-1925 350);
FORCEPROP 2 LAST CUSTOM_TXT_CDS <XR_PAGE_TITLE>
J 0
(-7890 5250);
DISPLAY 0.638298 (-7890 5250);
PAINT PINK (-7890 5250);
DISPLAY INVISIBLE (-7890 5250);
FORCEPROP 1 LAST SCH_ADDRESS3 Santa Clara, CA 95052-8119
J 0
(-3975 25);
DISPLAY 0.617021 (-3975 25);
PAINT GREEN (-3975 25);
FORCEPROP 1 LAST SCH_ADDRESS2 P.O. BOX 58119
J 0
(-3975 75);
DISPLAY 0.617021 (-3975 75);
PAINT GREEN (-3975 75);
FORCEPROP 1 LAST SCH_ADDRESS1 2200 Mission College Blvd.
J 0
(-3975 125);
DISPLAY 0.617021 (-3975 125);
PAINT GREEN (-3975 125);
FORCEPROP 1 LAST SCH_TITLE SKYLAKE - SKT1 - 16 OF 21
J 0
(-7950 50);
DISPLAY 1.212766 (-7950 50);
PAINT GREEN (-7950 50);
FORCEPROP 1 LAST SCH_NUMBER H4694802
J 0
(-1300 150);
DISPLAY 1.212766 (-1300 150);
PAINT YELLOW (-1300 150);
FORCEPROP 1 LAST SCH_DEPT BESD
J 1
(-4450 100);
DISPLAY 1.212766 (-4450 100);
PAINT YELLOW (-4450 100);
FORCEPROP 1 LAST SCH_REV 2.420
J 0
(-250 150);
DISPLAY 0.978723 (-250 150);
PAINT YELLOW (-250 150);
FORCEPROP 2 LAST PAGE_BORDER TRUE
J 0
(-7890 5250);
DISPLAY 0.851064 (-7890 5250);
PAINT PINK (-7890 5250);
DISPLAY INVISIBLE (-7890 5250);
FORCEPROP 2 LAST CDS_LIB mstr_symbols
J 0
(0 0);
PAINT ORANGE (0 0);
DISPLAY INVISIBLE (0 0);
FORCEPROP 1 LAST COMMENT_BODY TRUE
J 0
(12 12);
DISPLAY 0.638298 (12 12);
PAINT GREEN (12 12);
DISPLAY INVISIBLE (12 12);
FORCEPROP 2 LAST CDS_XR_PAGE_TITLE CR-70 : @BASEBOARD_FAB2_LIB.BASEBOARD_FAB2(SCH_1):PAGE70
J 0
(-7890 5250);
DISPLAY 0.638298 (-7890 5250);
PAINT PINK (-7890 5250);
DISPLAY INVISIBLE (-7890 5250);
FORCEADD DESIGN_NOTE..1
(-7550 3900);
FORCEPROP 0 LAST L1 MCP CLK IS USED FOR DEBUG ONLY
J 0
(-7725 3775);
DISPLAY 1.021277 (-7725 3775);
PAINT ORANGE (-7725 3775);
FORCEPROP 2 LAST CDS_LIB mstr_symbols
J 0
(-7550 3900);
PAINT ORANGE (-7550 3900);
DISPLAY INVISIBLE (-7550 3900);
FORCEPROP 1 LAST COMMENT_BODY TRUE
J 0
(-7525 4000);
DISPLAY 0.978723 (-7525 4000);
PAINT ORANGE (-7525 4000);
DISPLAY INVISIBLE (-7525 4000);
WIRE 16 -1 (-2225 2475)(-2050 2475);
WIRE 16 -1 (-2050 2475)(-2050 2525);
WIRE 16 -1 (-2225 2525)(-2050 2525);
WIRE 16 -1 (-2050 2525)(-2050 2575);
WIRE 16 -1 (-2225 2575)(-2050 2575);
WIRE 16 -1 (-2050 2575)(-2050 2625);
WIRE 16 -1 (-2225 2625)(-2050 2625);
WIRE 16 -1 (-2050 2625)(-1225 2625);
WIRE 16 -1 (-1225 2375)(-1225 2625);
WIRE 16 -1 (-1225 2625)(-1225 2775);
WIRE 16 -1 (-1225 2225)(-1225 2375);
WIRE 16 -1 (-2050 2375)(-1225 2375);
WIRE 16 -1 (-2050 2325)(-2050 2375);
WIRE 16 -1 (-2225 2375)(-2050 2375);
WIRE 16 -1 (-2225 2225)(-1225 2225);
WIRE 16 -1 (-2225 2325)(-2050 2325);
WIRE 16 -1 (-4850 1950)(-4000 1950);
WIRE 16 -1 (-4000 1950)(-4000 2000);
WIRE 16 -1 (-4850 2000)(-4000 2000);
WIRE 16 -1 (-4000 2000)(-4000 2150);
WIRE 16 -1 (-4850 2150)(-4000 2150);
WIRE 16 -1 (-4000 2150)(-4000 2250);
WIRE 16 -1 (-4850 2250)(-4000 2250);
WIRE 16 -1 (-4000 2250)(-4000 2450);
WIRE 16 -1 (-4850 2450)(-4000 2450);
WIRE 16 -1 (-4000 2450)(-4000 2500);
WIRE 16 -1 (-4850 2500)(-4000 2500);
WIRE 16 -1 (-4000 2500)(-4000 2550);
WIRE 16 -1 (-4850 2550)(-4000 2550);
WIRE 16 -1 (-4000 2550)(-4000 2700);
WIRE 16 -1 (-4850 2700)(-4000 2700);
WIRE 16 -1 (-4000 2700)(-4000 2800);
WIRE 16 -1 (-4850 2800)(-4000 2800);
WIRE 16 -1 (-4000 2800)(-4000 2850);
WIRE 16 -1 (-4850 2850)(-4000 2850);
WIRE 16 -1 (-4000 2850)(-4000 2950);
WIRE 16 -1 (-4850 2950)(-4000 2950);
WIRE 16 -1 (-4000 2950)(-4000 3100);
WIRE 16 -1 (-4850 3100)(-4000 3100);
WIRE 16 -1 (-4000 3100)(-4000 3150);
WIRE 16 -1 (-4850 3150)(-4000 3150);
WIRE 16 -1 (-4000 3150)(-4000 3250);
WIRE 16 -1 (-4850 3250)(-4000 3250);
WIRE 16 -1 (-4000 3250)(-4000 3350);
WIRE 16 -1 (-4850 3350)(-4000 3350);
WIRE 16 -1 (-4000 3350)(-4000 3450);
WIRE 16 -1 (-4850 3450)(-4000 3450);
WIRE 16 -1 (-4000 3450)(-4000 3600);
WIRE 16 -1 (-4850 3600)(-4000 3600);
WIRE 16 -1 (-4000 3600)(-4000 3650);
WIRE 16 -1 (-4850 3650)(-4000 3650);
WIRE 16 -1 (-4000 3650)(-4000 3725);
WIRE 16 -1 (-6050 1450)(-7125 1450);
WIRE 16 -1 (-7125 1450)(-7125 1500);
WIRE 16 -1 (-6050 1500)(-7125 1500);
WIRE 16 -1 (-7125 1500)(-7125 1550);
WIRE 16 -1 (-6050 1550)(-7125 1550);
WIRE 16 -1 (-7125 1550)(-7125 1600);
WIRE 16 -1 (-6050 1600)(-7125 1600);
WIRE 16 -1 (-7125 1600)(-7125 1650);
WIRE 16 -1 (-6050 1650)(-7125 1650);
WIRE 16 -1 (-7125 1650)(-7125 1700);
WIRE 16 -1 (-6050 1700)(-7125 1700);
WIRE 16 -1 (-7125 1700)(-7125 1750);
WIRE 16 -1 (-6050 1750)(-7125 1750);
WIRE 16 -1 (-7125 1750)(-7125 1800);
WIRE 16 -1 (-6050 1800)(-7125 1800);
WIRE 16 -1 (-7125 1800)(-7125 1850);
WIRE 16 -1 (-6050 1850)(-7125 1850);
WIRE 16 -1 (-7125 1850)(-7125 1900);
WIRE 16 -1 (-6050 1900)(-7125 1900);
WIRE 16 -1 (-7125 1900)(-7125 1950);
WIRE 16 -1 (-6050 1950)(-7125 1950);
WIRE 16 -1 (-7125 1950)(-7125 2000);
WIRE 16 -1 (-6050 2000)(-7125 2000);
WIRE 16 -1 (-7125 2000)(-7125 2050);
WIRE 16 -1 (-6050 2050)(-7125 2050);
WIRE 16 -1 (-7125 2050)(-7125 2100);
WIRE 16 -1 (-6050 2100)(-7125 2100);
WIRE 16 -1 (-7125 2100)(-7125 2150);
WIRE 16 -1 (-6050 2150)(-7125 2150);
WIRE 16 -1 (-7125 2150)(-7125 2200);
WIRE 16 -1 (-6050 2200)(-7125 2200);
WIRE 16 -1 (-7125 2200)(-7125 2250);
WIRE 16 -1 (-6050 2250)(-7125 2250);
WIRE 16 -1 (-7125 2250)(-7125 2300);
WIRE 16 -1 (-6725 2300)(-6050 2300);
FORCEPROP 2 LAST SIG_NAME TP_CPU1_RSVD_144
J 0
(-6717 2309);
DISPLAY 0.617021 (-6717 2309);
PAINT ORANGE (-6717 2309);
FORCEPROP 2 LASTPROP $XRERR UNIQUE?
J 0
(-6965 2300);
DISPLAY 0.638298 (-6965 2300);
PAINT MONO (-6965 2300);
DISPLAY INVISIBLE (-6965 2300);
WIRE 16 -1 (-6725 2900)(-6050 2900);
FORCEPROP 2 LAST SIG_NAME TP_CPU1_RSVD_156
J 0
(-6717 2909);
DISPLAY 0.617021 (-6717 2909);
PAINT ORANGE (-6717 2909);
FORCEPROP 2 LASTPROP $XRERR UNIQUE?
J 0
(-6965 2900);
DISPLAY 0.638298 (-6965 2900);
PAINT MONO (-6965 2900);
DISPLAY INVISIBLE (-6965 2900);
WIRE 16 -1 (-6725 2950)(-6050 2950);
FORCEPROP 2 LAST SIG_NAME TP_CPU1_RSVD_157
J 0
(-6717 2959);
DISPLAY 0.617021 (-6717 2959);
PAINT ORANGE (-6717 2959);
FORCEPROP 2 LASTPROP $XRERR UNIQUE?
J 0
(-6965 2950);
DISPLAY 0.638298 (-6965 2950);
PAINT MONO (-6965 2950);
DISPLAY INVISIBLE (-6965 2950);
WIRE 16 -1 (-6725 3000)(-6050 3000);
FORCEPROP 2 LAST SIG_NAME TP_CPU1_RSVD_158
J 0
(-6717 3009);
DISPLAY 0.617021 (-6717 3009);
PAINT ORANGE (-6717 3009);
FORCEPROP 2 LASTPROP $XRERR UNIQUE?
J 0
(-6965 3000);
DISPLAY 0.638298 (-6965 3000);
PAINT MONO (-6965 3000);
DISPLAY INVISIBLE (-6965 3000);
WIRE 16 -1 (-6725 3100)(-6050 3100);
FORCEPROP 2 LAST SIG_NAME TP_CPU1_RSVD_160
J 0
(-6717 3109);
DISPLAY 0.617021 (-6717 3109);
PAINT ORANGE (-6717 3109);
FORCEPROP 2 LASTPROP $XRERR UNIQUE?
J 0
(-6965 3100);
DISPLAY 0.638298 (-6965 3100);
PAINT MONO (-6965 3100);
DISPLAY INVISIBLE (-6965 3100);
WIRE 16 -1 (-6725 3150)(-6050 3150);
FORCEPROP 2 LAST SIG_NAME TP_CPU1_RSVD_161
J 0
(-6717 3159);
DISPLAY 0.617021 (-6717 3159);
PAINT ORANGE (-6717 3159);
FORCEPROP 2 LASTPROP $XRERR UNIQUE?
J 0
(-6965 3150);
DISPLAY 0.638298 (-6965 3150);
PAINT MONO (-6965 3150);
DISPLAY INVISIBLE (-6965 3150);
WIRE 16 -1 (-6725 3200)(-6050 3200);
FORCEPROP 2 LAST SIG_NAME TP_CPU1_RSVD_162
J 0
(-6717 3209);
DISPLAY 0.617021 (-6717 3209);
PAINT ORANGE (-6717 3209);
FORCEPROP 2 LASTPROP $XRERR UNIQUE?
J 0
(-6965 3200);
DISPLAY 0.638298 (-6965 3200);
PAINT MONO (-6965 3200);
DISPLAY INVISIBLE (-6965 3200);
WIRE 16 -1 (-6725 3250)(-6050 3250);
FORCEPROP 2 LAST SIG_NAME TP_CPU1_RSVD_163
J 0
(-6717 3259);
DISPLAY 0.617021 (-6717 3259);
PAINT ORANGE (-6717 3259);
FORCEPROP 2 LASTPROP $XRERR UNIQUE?
J 0
(-6965 3250);
DISPLAY 0.638298 (-6965 3250);
PAINT MONO (-6965 3250);
DISPLAY INVISIBLE (-6965 3250);
WIRE 16 -1 (-6725 3300)(-6050 3300);
FORCEPROP 2 LAST SIG_NAME TP_CPU1_RSVD_164
J 0
(-6717 3309);
DISPLAY 0.617021 (-6717 3309);
PAINT ORANGE (-6717 3309);
FORCEPROP 2 LASTPROP $XRERR UNIQUE?
J 0
(-6965 3300);
DISPLAY 0.638298 (-6965 3300);
PAINT MONO (-6965 3300);
DISPLAY INVISIBLE (-6965 3300);
WIRE 16 -1 (-6725 3400)(-6050 3400);
FORCEPROP 2 LAST SIG_NAME TP_CPU1_RSVD_166
J 0
(-6717 3409);
DISPLAY 0.617021 (-6717 3409);
PAINT ORANGE (-6717 3409);
FORCEPROP 2 LASTPROP $XRERR UNIQUE?
J 0
(-6965 3400);
DISPLAY 0.638298 (-6965 3400);
PAINT MONO (-6965 3400);
DISPLAY INVISIBLE (-6965 3400);
WIRE 16 -1 (-6725 3450)(-6050 3450);
FORCEPROP 2 LAST SIG_NAME TP_CPU1_RSVD_167
J 0
(-6717 3459);
DISPLAY 0.617021 (-6717 3459);
PAINT ORANGE (-6717 3459);
FORCEPROP 2 LASTPROP $XRERR UNIQUE?
J 0
(-6965 3450);
DISPLAY 0.638298 (-6965 3450);
PAINT MONO (-6965 3450);
DISPLAY INVISIBLE (-6965 3450);
WIRE 16 -1 (-6725 3500)(-6050 3500);
FORCEPROP 2 LAST SIG_NAME TP_CPU1_RSVD_168
J 0
(-6717 3509);
DISPLAY 0.617021 (-6717 3509);
PAINT ORANGE (-6717 3509);
FORCEPROP 2 LASTPROP $XRERR UNIQUE?
J 0
(-6965 3500);
DISPLAY 0.638298 (-6965 3500);
PAINT MONO (-6965 3500);
DISPLAY INVISIBLE (-6965 3500);
WIRE 16 -1 (-6725 3550)(-6050 3550);
FORCEPROP 2 LAST SIG_NAME TP_CPU1_RSVD_169
J 0
(-6717 3559);
DISPLAY 0.617021 (-6717 3559);
PAINT ORANGE (-6717 3559);
FORCEPROP 2 LASTPROP $XRERR UNIQUE?
J 0
(-6965 3550);
DISPLAY 0.638298 (-6965 3550);
PAINT MONO (-6965 3550);
DISPLAY INVISIBLE (-6965 3550);
WIRE 16 -1 (-6725 3600)(-6050 3600);
FORCEPROP 2 LAST SIG_NAME TP_CPU1_RSVD_170
J 0
(-6717 3609);
DISPLAY 0.617021 (-6717 3609);
PAINT ORANGE (-6717 3609);
FORCEPROP 2 LASTPROP $XRERR UNIQUE?
J 0
(-6965 3600);
DISPLAY 0.638298 (-6965 3600);
PAINT MONO (-6965 3600);
DISPLAY INVISIBLE (-6965 3600);
WIRE 16 -1 (-6725 3650)(-6050 3650);
FORCEPROP 2 LAST SIG_NAME TP_CPU1_RSVD_171
J 0
(-6717 3659);
DISPLAY 0.617021 (-6717 3659);
PAINT ORANGE (-6717 3659);
FORCEPROP 2 LASTPROP $XRERR UNIQUE?
J 0
(-6965 3650);
DISPLAY 0.638298 (-6965 3650);
PAINT MONO (-6965 3650);
DISPLAY INVISIBLE (-6965 3650);
WIRE 16 -1 (-6725 2800)(-6050 2800);
FORCEPROP 2 LAST SIG_NAME TP_CPU1_RSVD_154
J 0
(-6717 2809);
DISPLAY 0.617021 (-6717 2809);
PAINT ORANGE (-6717 2809);
FORCEPROP 2 LASTPROP $XRERR UNIQUE?
J 0
(-6965 2800);
DISPLAY 0.638298 (-6965 2800);
PAINT MONO (-6965 2800);
DISPLAY INVISIBLE (-6965 2800);
WIRE 16 -1 (-6725 2600)(-6050 2600);
FORCEPROP 2 LAST SIG_NAME TP_CPU1_RSVD_150
J 0
(-6717 2609);
DISPLAY 0.617021 (-6717 2609);
PAINT ORANGE (-6717 2609);
FORCEPROP 2 LASTPROP $XRERR UNIQUE?
J 0
(-6965 2600);
DISPLAY 0.638298 (-6965 2600);
PAINT MONO (-6965 2600);
DISPLAY INVISIBLE (-6965 2600);
WIRE 16 -1 (-6725 2650)(-6050 2650);
FORCEPROP 2 LAST SIG_NAME TP_CPU1_RSVD_151
J 0
(-6717 2659);
DISPLAY 0.617021 (-6717 2659);
PAINT ORANGE (-6717 2659);
FORCEPROP 2 LASTPROP $XRERR UNIQUE?
J 0
(-6965 2650);
DISPLAY 0.638298 (-6965 2650);
PAINT MONO (-6965 2650);
DISPLAY INVISIBLE (-6965 2650);
WIRE 16 -1 (-6725 2850)(-6050 2850);
FORCEPROP 2 LAST SIG_NAME TP_CPU1_RSVD_155
J 0
(-6717 2859);
DISPLAY 0.617021 (-6717 2859);
PAINT ORANGE (-6717 2859);
FORCEPROP 2 LASTPROP $XRERR UNIQUE?
J 0
(-6965 2850);
DISPLAY 0.638298 (-6965 2850);
PAINT MONO (-6965 2850);
DISPLAY INVISIBLE (-6965 2850);
WIRE 16 -1 (-6725 3050)(-6050 3050);
FORCEPROP 2 LAST SIG_NAME TP_CPU1_RSVD_159
J 0
(-6717 3059);
DISPLAY 0.617021 (-6717 3059);
PAINT ORANGE (-6717 3059);
FORCEPROP 2 LASTPROP $XRERR UNIQUE?
J 0
(-6965 3050);
DISPLAY 0.638298 (-6965 3050);
PAINT MONO (-6965 3050);
DISPLAY INVISIBLE (-6965 3050);
WIRE 16 -1 (-6725 2350)(-6050 2350);
FORCEPROP 2 LAST SIG_NAME TP_CPU1_RSVD_145
J 0
(-6717 2359);
DISPLAY 0.617021 (-6717 2359);
PAINT ORANGE (-6717 2359);
FORCEPROP 2 LASTPROP $XRERR UNIQUE?
J 0
(-6965 2350);
DISPLAY 0.638298 (-6965 2350);
PAINT MONO (-6965 2350);
DISPLAY INVISIBLE (-6965 2350);
WIRE 16 -1 (-6725 2400)(-6050 2400);
FORCEPROP 2 LAST SIG_NAME TP_CPU1_RSVD_146
J 0
(-6717 2409);
DISPLAY 0.617021 (-6717 2409);
PAINT ORANGE (-6717 2409);
FORCEPROP 2 LASTPROP $XRERR UNIQUE?
J 0
(-6965 2400);
DISPLAY 0.638298 (-6965 2400);
PAINT MONO (-6965 2400);
DISPLAY INVISIBLE (-6965 2400);
WIRE 16 -1 (-6725 2450)(-6050 2450);
FORCEPROP 2 LAST SIG_NAME TP_CPU1_RSVD_147
J 0
(-6717 2459);
DISPLAY 0.617021 (-6717 2459);
PAINT ORANGE (-6717 2459);
FORCEPROP 2 LASTPROP $XRERR UNIQUE?
J 0
(-6965 2450);
DISPLAY 0.638298 (-6965 2450);
PAINT MONO (-6965 2450);
DISPLAY INVISIBLE (-6965 2450);
WIRE 16 -1 (-6725 2550)(-6050 2550);
FORCEPROP 2 LAST SIG_NAME TP_CPU1_RSVD_149
J 0
(-6717 2559);
DISPLAY 0.617021 (-6717 2559);
PAINT ORANGE (-6717 2559);
FORCEPROP 2 LASTPROP $XRERR UNIQUE?
J 0
(-6965 2550);
DISPLAY 0.638298 (-6965 2550);
PAINT MONO (-6965 2550);
DISPLAY INVISIBLE (-6965 2550);
WIRE 16 -1 (-6725 2500)(-6050 2500);
FORCEPROP 2 LAST SIG_NAME TP_CPU1_RSVD_148
J 0
(-6717 2509);
DISPLAY 0.617021 (-6717 2509);
PAINT ORANGE (-6717 2509);
FORCEPROP 2 LASTPROP $XRERR UNIQUE?
J 0
(-6965 2500);
DISPLAY 0.638298 (-6965 2500);
PAINT MONO (-6965 2500);
DISPLAY INVISIBLE (-6965 2500);
WIRE 16 -1 (-6725 2700)(-6050 2700);
FORCEPROP 2 LAST SIG_NAME TP_CPU1_RSVD_152
J 0
(-6717 2709);
DISPLAY 0.617021 (-6717 2709);
PAINT ORANGE (-6717 2709);
FORCEPROP 2 LASTPROP $XRERR UNIQUE?
J 0
(-6965 2700);
DISPLAY 0.638298 (-6965 2700);
PAINT MONO (-6965 2700);
DISPLAY INVISIBLE (-6965 2700);
WIRE 16 -1 (-6975 3350)(-6050 3350);
FORCEPROP 2 LAST SIG_NAME CLK_100M_CPU1_RC_REFCLK1_DN
J 0
(-6942 3359);
DISPLAY 0.617021 (-6942 3359);
PAINT ORANGE (-6942 3359);
WIRE 16 -1 (-6975 2750)(-6050 2750);
FORCEPROP 2 LAST SIG_NAME CLK_100M_CPU1_RC_REFCLK1_DP
J 0
(-6942 2759);
DISPLAY 0.617021 (-6942 2759);
PAINT ORANGE (-6942 2759);
WIRE 16 -1 (-4175 1900)(-4850 1900);
FORCEPROP 2 LAST SIG_NAME TP_CPU1_RSVD_255
J 0
(-4692 1909);
DISPLAY 0.617021 (-4692 1909);
PAINT ORANGE (-4692 1909);
FORCEPROP 2 LASTPROP $XRERR UNIQUE?
J 0
(-4145 1900);
DISPLAY 0.638298 (-4145 1900);
PAINT MONO (-4145 1900);
DISPLAY INVISIBLE (-4145 1900);
WIRE 16 -1 (-4175 2050)(-4850 2050);
FORCEPROP 2 LAST SIG_NAME TP_CPU1_RSVD_94
J 0
(-4692 2059);
DISPLAY 0.617021 (-4692 2059);
PAINT ORANGE (-4692 2059);
FORCEPROP 2 LASTPROP $XRERR UNIQUE?
J 0
(-4145 2050);
DISPLAY 0.638298 (-4145 2050);
PAINT MONO (-4145 2050);
DISPLAY INVISIBLE (-4145 2050);
WIRE 16 -1 (-4175 2100)(-4850 2100);
FORCEPROP 2 LAST SIG_NAME TP_CPU1_RSVD_95
J 0
(-4692 2109);
DISPLAY 0.617021 (-4692 2109);
PAINT ORANGE (-4692 2109);
FORCEPROP 2 LASTPROP $XRERR UNIQUE?
J 0
(-4145 2100);
DISPLAY 0.638298 (-4145 2100);
PAINT MONO (-4145 2100);
DISPLAY INVISIBLE (-4145 2100);
WIRE 16 -1 (-4175 2400)(-4850 2400);
FORCEPROP 2 LAST SIG_NAME TP_CPU1_RSVD_101
J 0
(-4692 2409);
DISPLAY 0.617021 (-4692 2409);
PAINT ORANGE (-4692 2409);
FORCEPROP 2 LASTPROP $XRERR UNIQUE?
J 0
(-4145 2400);
DISPLAY 0.638298 (-4145 2400);
PAINT MONO (-4145 2400);
DISPLAY INVISIBLE (-4145 2400);
WIRE 16 -1 (-4850 2600)(-4175 2600);
FORCEPROP 2 LAST SIG_NAME TP_CPU1_RSVD_105
J 0
(-4692 2609);
DISPLAY 0.617021 (-4692 2609);
PAINT ORANGE (-4692 2609);
FORCEPROP 2 LASTPROP $XRERR UNIQUE?
J 0
(-4145 2600);
DISPLAY 0.638298 (-4145 2600);
PAINT MONO (-4145 2600);
DISPLAY INVISIBLE (-4145 2600);
WIRE 16 -1 (-4175 2650)(-4850 2650);
FORCEPROP 2 LAST SIG_NAME TP_CPU1_RSVD_106
J 0
(-4692 2659);
DISPLAY 0.617021 (-4692 2659);
PAINT ORANGE (-4692 2659);
FORCEPROP 2 LASTPROP $XRERR UNIQUE?
J 0
(-4145 2650);
DISPLAY 0.638298 (-4145 2650);
PAINT MONO (-4145 2650);
DISPLAY INVISIBLE (-4145 2650);
WIRE 16 -1 (-4175 2750)(-4850 2750);
FORCEPROP 2 LAST SIG_NAME TP_CPU1_RSVD_108
J 0
(-4692 2759);
DISPLAY 0.617021 (-4692 2759);
PAINT ORANGE (-4692 2759);
FORCEPROP 2 LASTPROP $XRERR UNIQUE?
J 0
(-4145 2750);
DISPLAY 0.638298 (-4145 2750);
PAINT MONO (-4145 2750);
DISPLAY INVISIBLE (-4145 2750);
WIRE 16 -1 (-4175 2900)(-4850 2900);
FORCEPROP 2 LAST SIG_NAME TP_CPU1_RSVD_111
J 0
(-4692 2909);
DISPLAY 0.617021 (-4692 2909);
PAINT ORANGE (-4692 2909);
FORCEPROP 2 LASTPROP $XRERR UNIQUE?
J 0
(-4145 2900);
DISPLAY 0.638298 (-4145 2900);
PAINT MONO (-4145 2900);
DISPLAY INVISIBLE (-4145 2900);
WIRE 16 -1 (-4175 3000)(-4850 3000);
FORCEPROP 2 LAST SIG_NAME TP_CPU1_RSVD_113
J 0
(-4692 3009);
DISPLAY 0.617021 (-4692 3009);
PAINT ORANGE (-4692 3009);
FORCEPROP 2 LASTPROP $XRERR UNIQUE?
J 0
(-4145 3000);
DISPLAY 0.638298 (-4145 3000);
PAINT MONO (-4145 3000);
DISPLAY INVISIBLE (-4145 3000);
WIRE 16 -1 (-4175 3050)(-4850 3050);
FORCEPROP 2 LAST SIG_NAME TP_CPU1_RSVD_114
J 0
(-4692 3059);
DISPLAY 0.617021 (-4692 3059);
PAINT ORANGE (-4692 3059);
FORCEPROP 2 LASTPROP $XRERR UNIQUE?
J 0
(-4145 3050);
DISPLAY 0.638298 (-4145 3050);
PAINT MONO (-4145 3050);
DISPLAY INVISIBLE (-4145 3050);
WIRE 16 -1 (-4175 2200)(-4850 2200);
FORCEPROP 2 LAST SIG_NAME TP_CPU1_RSVD_97
J 0
(-4692 2209);
DISPLAY 0.617021 (-4692 2209);
PAINT ORANGE (-4692 2209);
FORCEPROP 2 LASTPROP $XRERR UNIQUE?
J 0
(-4145 2200);
DISPLAY 0.638298 (-4145 2200);
PAINT MONO (-4145 2200);
DISPLAY INVISIBLE (-4145 2200);
WIRE 16 -1 (-4175 2300)(-4850 2300);
FORCEPROP 2 LAST SIG_NAME TP_CPU1_RSVD_99
J 0
(-4692 2309);
DISPLAY 0.617021 (-4692 2309);
PAINT ORANGE (-4692 2309);
FORCEPROP 2 LASTPROP $XRERR UNIQUE?
J 0
(-4145 2300);
DISPLAY 0.638298 (-4145 2300);
PAINT MONO (-4145 2300);
DISPLAY INVISIBLE (-4145 2300);
WIRE 16 -1 (-4175 2350)(-4850 2350);
FORCEPROP 2 LAST SIG_NAME TP_CPU1_RSVD_100
J 0
(-4692 2359);
DISPLAY 0.617021 (-4692 2359);
PAINT ORANGE (-4692 2359);
FORCEPROP 2 LASTPROP $XRERR UNIQUE?
J 0
(-4145 2350);
DISPLAY 0.638298 (-4145 2350);
PAINT MONO (-4145 2350);
DISPLAY INVISIBLE (-4145 2350);
WIRE 16 -1 (-4175 3200)(-4850 3200);
FORCEPROP 2 LAST SIG_NAME TP_CPU1_RSVD_117
J 0
(-4692 3209);
DISPLAY 0.617021 (-4692 3209);
PAINT ORANGE (-4692 3209);
FORCEPROP 2 LASTPROP $XRERR UNIQUE?
J 0
(-4145 3200);
DISPLAY 0.638298 (-4145 3200);
PAINT MONO (-4145 3200);
DISPLAY INVISIBLE (-4145 3200);
WIRE 16 -1 (-4175 3300)(-4850 3300);
FORCEPROP 2 LAST SIG_NAME TP_CPU1_RSVD_119
J 0
(-4692 3309);
DISPLAY 0.617021 (-4692 3309);
PAINT ORANGE (-4692 3309);
FORCEPROP 2 LASTPROP $XRERR UNIQUE?
J 0
(-4145 3300);
DISPLAY 0.638298 (-4145 3300);
PAINT MONO (-4145 3300);
DISPLAY INVISIBLE (-4145 3300);
WIRE 16 -1 (-4175 3400)(-4850 3400);
FORCEPROP 2 LAST SIG_NAME TP_CPU1_RSVD_121
J 0
(-4692 3409);
DISPLAY 0.617021 (-4692 3409);
PAINT ORANGE (-4692 3409);
FORCEPROP 2 LASTPROP $XRERR UNIQUE?
J 0
(-4145 3400);
DISPLAY 0.638298 (-4145 3400);
PAINT MONO (-4145 3400);
DISPLAY INVISIBLE (-4145 3400);
WIRE 16 -1 (-4175 3500)(-4850 3500);
FORCEPROP 2 LAST SIG_NAME TP_CPU1_RSVD_123
J 0
(-4692 3509);
DISPLAY 0.617021 (-4692 3509);
PAINT ORANGE (-4692 3509);
FORCEPROP 2 LASTPROP $XRERR UNIQUE?
J 0
(-4145 3500);
DISPLAY 0.638298 (-4145 3500);
PAINT MONO (-4145 3500);
DISPLAY INVISIBLE (-4145 3500);
WIRE 16 -1 (-4175 3550)(-4850 3550);
FORCEPROP 2 LAST SIG_NAME TP_CPU1_RSVD_124
J 0
(-4692 3559);
DISPLAY 0.617021 (-4692 3559);
PAINT ORANGE (-4692 3559);
FORCEPROP 2 LASTPROP $XRERR UNIQUE?
J 0
(-4145 3550);
DISPLAY 0.638298 (-4145 3550);
PAINT MONO (-4145 3550);
DISPLAY INVISIBLE (-4145 3550);
WIRE 16 -1 (-1550 2925)(-2225 2925);
FORCEPROP 2 LAST SIG_NAME TP_CPU1_TEST_9
J 0
(-2075 2935);
DISPLAY 0.617021 (-2075 2935);
PAINT ORANGE (-2075 2935);
FORCEPROP 2 LASTPROP $XRERR UNIQUE?
J 0
(-1520 2925);
DISPLAY 0.638298 (-1520 2925);
PAINT MONO (-1520 2925);
DISPLAY INVISIBLE (-1520 2925);
WIRE 16 -1 (-1550 2975)(-2225 2975);
FORCEPROP 2 LAST SIG_NAME TP_CPU1_TEST_8
J 0
(-2075 2985);
DISPLAY 0.617021 (-2075 2985);
PAINT ORANGE (-2075 2985);
FORCEPROP 2 LASTPROP $XRERR UNIQUE?
J 0
(-1520 2975);
DISPLAY 0.638298 (-1520 2975);
PAINT MONO (-1520 2975);
DISPLAY INVISIBLE (-1520 2975);
WIRE 16 -1 (-2225 3025)(-1550 3025);
FORCEPROP 2 LAST SIG_NAME TP_CPU1_TEST_7
J 0
(-2075 3035);
DISPLAY 0.617021 (-2075 3035);
PAINT ORANGE (-2075 3035);
FORCEPROP 2 LASTPROP $XRERR UNIQUE?
J 0
(-1520 3025);
DISPLAY 0.638298 (-1520 3025);
PAINT MONO (-1520 3025);
DISPLAY INVISIBLE (-1520 3025);
WIRE 16 -1 (-1550 3075)(-2225 3075);
FORCEPROP 2 LAST SIG_NAME TP_CPU1_TEST_6
J 0
(-2075 3085);
DISPLAY 0.617021 (-2075 3085);
PAINT ORANGE (-2075 3085);
FORCEPROP 2 LASTPROP $XRERR UNIQUE?
J 0
(-1520 3075);
DISPLAY 0.638298 (-1520 3075);
PAINT MONO (-1520 3075);
DISPLAY INVISIBLE (-1520 3075);
WIRE 16 -1 (-1550 2875)(-2225 2875);
FORCEPROP 2 LAST SIG_NAME TP_CPU1_TEST_10
J 0
(-2075 2885);
DISPLAY 0.617021 (-2075 2885);
PAINT ORANGE (-2075 2885);
FORCEPROP 2 LASTPROP $XRERR UNIQUE?
J 0
(-1520 2875);
DISPLAY 0.638298 (-1520 2875);
PAINT MONO (-1520 2875);
DISPLAY INVISIBLE (-1520 2875);
WIRE 16 -1 (-1550 2275)(-2225 2275);
FORCEPROP 2 LAST SIG_NAME TP_CPU1_RSVD_82
J 0
(-2075 2285);
DISPLAY 0.617021 (-2075 2285);
PAINT ORANGE (-2075 2285);
FORCEPROP 2 LASTPROP $XRERR UNIQUE?
J 0
(-1520 2275);
DISPLAY 0.638298 (-1520 2275);
PAINT MONO (-1520 2275);
DISPLAY INVISIBLE (-1520 2275);
WIRE 16 -1 (-2225 2425)(-1550 2425);
FORCEPROP 2 LAST SIG_NAME TP_CPU1_RSVD_85
J 0
(-2075 2435);
DISPLAY 0.617021 (-2075 2435);
PAINT ORANGE (-2075 2435);
FORCEPROP 2 LASTPROP $XRERR UNIQUE?
J 0
(-1520 2425);
DISPLAY 0.638298 (-1520 2425);
PAINT MONO (-1520 2425);
DISPLAY INVISIBLE (-1520 2425);
WIRE 16 -1 (-1550 2725)(-2225 2725);
FORCEPROP 2 LAST SIG_NAME TP_CPU1_RSVD_90
J 0
(-2075 2735);
DISPLAY 0.617021 (-2075 2735);
PAINT ORANGE (-2075 2735);
FORCEPROP 2 LASTPROP $XRERR UNIQUE?
J 0
(-1520 2725);
DISPLAY 0.638298 (-1520 2725);
PAINT MONO (-1520 2725);
DISPLAY INVISIBLE (-1520 2725);
WIRE 16 -1 (-1550 2775)(-2225 2775);
FORCEPROP 2 LAST SIG_NAME TP_CPU1_RSVD_91
J 0
(-2075 2785);
DISPLAY 0.617021 (-2075 2785);
PAINT ORANGE (-2075 2785);
FORCEPROP 2 LASTPROP $XRERR UNIQUE?
J 0
(-1520 2775);
DISPLAY 0.638298 (-1520 2775);
PAINT MONO (-1520 2775);
DISPLAY INVISIBLE (-1520 2775);
DOT 1 (-7125 1550);
DOT 1 (-7125 1500);
DOT 1 (-4000 2800);
DOT 1 (-7125 2250);
DOT 1 (-7125 2150);
DOT 1 (-7125 2100);
DOT 1 (-7125 2050);
DOT 1 (-7125 2000);
DOT 1 (-7125 1950);
DOT 1 (-7125 1900);
DOT 1 (-7125 1850);
DOT 1 (-7125 1800);
DOT 1 (-7125 1750);
DOT 1 (-7125 1700);
DOT 1 (-7125 1650);
DOT 1 (-7125 1600);
DOT 1 (-4000 3650);
DOT 1 (-4000 3600);
DOT 1 (-4000 3450);
DOT 1 (-4000 3350);
DOT 1 (-4000 3250);
DOT 1 (-4000 3150);
DOT 1 (-4000 3100);
DOT 1 (-4000 2950);
DOT 1 (-4000 2850);
DOT 1 (-4000 2700);
DOT 1 (-4000 2550);
DOT 1 (-4000 2500);
DOT 1 (-4000 2450);
DOT 1 (-4000 2250);
DOT 1 (-4000 2150);
DOT 1 (-4000 2000);
DOT 1 (-1225 2375);
DOT 1 (-1225 2625);
DOT 1 (-2050 2375);
DOT 1 (-2050 2525);
DOT 1 (-2050 2575);
DOT 1 (-2050 2625);
DOT 1 (-7125 2200);
FORCENOTE
BOM_COST=PROC_SOCKET
(-7925 200) 0;
DISPLAY LEFT (-7925 200);
DISPLAY 1.723404 (-7925 200);
PAINT PURPLE (-7925 200);
FORCENOTE
ROOM=CPU1
(-7925 325) 0;
DISPLAY LEFT (-7925 325);
DISPLAY 1.723404 (-7925 325);
PAINT PURPLE (-7925 325);
QUIT
